# S9S_MB_2U (Grand Teton) — schematic netlist excerpt (pin names and nets, part order shuffled) for the footprints in the layout excerpt that follows; sources: Cadence DE-HDL packaged netlist, KiCad conversion of 03242023_DA0F0TMBIJ0_F0T_Motherboard_J_brd_V01_OCP.brd

J119  PICOPROBE_BXA  DELTA-L 4.0 EMPTY  pkg TRIANG_LAUNCH_3PXB  page 308
  \1_p\  = DELTA_L_85_10INCH_IN6_DP
  \2_n\  = DELTA_L_85_10INCH_IN6_DN
  \3_g\  = DELTA_L_GND_1

(kicad_pcb
	(version 20260206)
	(generator "pcbnew")
	(generator_version "10.0")
	(general
		(thickness 1.6)
		(legacy_teardrops no)
	)
	(paper "A4")
	(title_block
		(title "03242023_DA0F0TMBIJ0_F0T_Motherboard_J_brd_V01_OCP.brd")
		(comment 1 "Grand Teton / footprints 5721-5721 of 6105")
	)
	(layers
		(0 "F.Cu" signal "TOP")
		(4 "In1.Cu" signal "GND")
		(6 "In2.Cu" signal "IN1")
		(8 "In3.Cu" signal "GND1")
		(10 "In4.Cu" signal "IN2")
		(12 "In5.Cu" signal "GND2")
		(14 "In6.Cu" signal "IN3")
		(16 "In7.Cu" signal "GND3")
		(18 "In8.Cu" signal "VCC")
		(20 "In9.Cu" signal "VCC1")
		(22 "In10.Cu" signal "GND4")
		(24 "In11.Cu" signal "IN4")
		(26 "In12.Cu" signal "GND5")
		(28 "In13.Cu" signal "IN5")
		(30 "In14.Cu" signal "GND6")
		(32 "In15.Cu" signal "IN6")
		(34 "In16.Cu" signal "GND7")
		(2 "B.Cu" signal "BOTTOM")
		(9 "F.Adhes" user "F.Adhesive")
		(11 "B.Adhes" user "B.Adhesive")
		(13 "F.Paste" user "Package Geometry/Pastemask Top")
		(15 "B.Paste" user "Package Geometry/Pastemask Bottom")
		(5 "F.SilkS" user "Ref Des/Silkscreen Top")
		(7 "B.SilkS" user "Ref Des/Silkscreen Bottom")
		(1 "F.Mask" user "Board Geometry/Soldermask Top")
		(3 "B.Mask" user "Board Geometry/Soldermask Bottom")
		(17 "Dwgs.User" user "User.Drawings")
		(19 "Cmts.User" user "User.Comments")
		(21 "Eco1.User" user "User.Eco1")
		(23 "Eco2.User" user "User.Eco2")
		(25 "Edge.Cuts" user "Board Geometry/Outline")
		(27 "Margin" user)
		(31 "F.CrtYd" user "Package Geometry/Place Bound Top")
		(29 "B.CrtYd" user "Package Geometry/Place Bound Bottom")
		(35 "F.Fab" user "Ref Des/Assembly Top")
		(33 "B.Fab" user "Ref Des/Assembly Bottom")
	)
	(footprint ""
		(layer "B.Cu")
		(at 329.240388 2.923794)
		(property "Reference" "J119"
			(at 4.361942 1.521206 270)
			(unlocked yes)
			(layer "B.SilkS")
			(effects
				(font
					(size 0.7874 0.5842)
					(thickness 0.1524)
				)
				(justify left mirror)
			)
		)
		(property "Value" ""
			(at 0 0 0)
			(layer "B.Fab")
			(effects
				(font
					(size 1.27 1.27)
				)
				(justify mirror)
			)
		)
		(duplicate_pad_numbers_are_jumpers no)
		(fp_line
			(start -1.2192 -2.1082)
			(end -1.2192 2.1082)
			(stroke
				(width 0.1524)
				(type default)
			)
			(layer "B.SilkS")
		)
		(fp_line
			(start -1.2192 2.1082)
			(end 1.2192 2.1082)
			(stroke
				(width 0.1524)
				(type default)
			)
			(layer "B.SilkS")
		)
		(fp_line
			(start 1.2192 -2.1082)
			(end -1.2192 -2.1082)
			(stroke
				(width 0.1524)
				(type default)
			)
			(layer "B.SilkS")
		)
		(fp_line
			(start 1.2192 2.1082)
			(end 1.2192 -2.1082)
			(stroke
				(width 0.1524)
				(type default)
			)
			(layer "B.SilkS")
		)
		(pad "" np_thru_hole circle
			(at -3.4671 -1.27 270)
			(size 1.0414 1.0414)
			(drill 1.0414)
			(layers "*.Cu" "*.Mask")
			(clearance 0.381)
			(thermal_gap 0.381)
		)
		(pad "" np_thru_hole circle
			(at -3.4671 1.27 270)
			(size 1.0414 1.0414)
			(drill 1.0414)
			(layers "*.Cu" "*.Mask")
			(clearance 0.381)
			(thermal_gap 0.381)
		)
		(pad "" np_thru_hole circle
			(at 2.8829 -1.27 270)
			(size 1.0414 1.0414)
			(drill 1.0414)
			(layers "*.Cu" "*.Mask")
			(clearance 0.381)
			(thermal_gap 0.381)
		)
		(pad "" np_thru_hole circle
			(at 2.8829 1.27 270)
			(size 1.0414 1.0414)
			(drill 1.0414)
			(layers "*.Cu" "*.Mask")
			(clearance 0.381)
			(thermal_gap 0.381)
		)
		(pad "1" smd rect
			(at -0.8255 -0.249936 270)
			(size 0.3048 0.508)
			(layers "B.Cu" "B.Mask" "B.Paste")
			(net "DELTA_L_85_10INCH_IN6_DP")
		)
		(pad "2" smd rect
			(at -0.8255 0.249936 270)
			(size 0.3048 0.508)
			(layers "B.Cu" "B.Mask" "B.Paste")
			(net "DELTA_L_85_10INCH_IN6_DN")
		)
		(pad "3" smd circle
			(at 0 0 180)
			(size 0 0)
			(layers "B.Cu" "B.Mask" "B.Paste")
			(net "DELTA_L_GND_1")
		)
		(zone
			(layers "F.Cu" "B.Cu" "In1.Cu" "In2.Cu" "In3.Cu" "In4.Cu" "In5.Cu" "In6.Cu"
				"In7.Cu" "In8.Cu" "In9.Cu" "In10.Cu" "In11.Cu" "In12.Cu" "In13.Cu" "In14.Cu"
				"In15.Cu" "In16.Cu"
			)
			(hatch none 0.5)
			(connect_pads
				(clearance 0)
			)
			(min_thickness 0.25)
			(keepout
				(tracks not_allowed)
				(vias allowed)
				(pads allowed)
				(copperpour not_allowed)
				(footprints allowed)
			)
			(placement
				(enabled no)
				(sheetname "")
			)
			(fill
				(thermal_gap 0.5)
				(thermal_bridge_width 0.5)
				(island_removal_mode 0)
			)
			(polygon
				(pts
					(arc
						(start 326.700388 1.653794)
						(mid 324.846188 1.653794)
						(end 326.700388 1.653794)
					)
				)
			)
		)
		(zone
			(layers "F.Cu" "B.Cu" "In1.Cu" "In2.Cu" "In3.Cu" "In4.Cu" "In5.Cu" "In6.Cu"
				"In7.Cu" "In8.Cu" "In9.Cu" "In10.Cu" "In11.Cu" "In12.Cu" "In13.Cu" "In14.Cu"
				"In15.Cu" "In16.Cu"
			)
			(hatch none 0.5)
			(connect_pads
				(clearance 0)
			)
			(min_thickness 0.25)
			(keepout
				(tracks not_allowed)
				(vias allowed)
				(pads allowed)
				(copperpour not_allowed)
				(footprints allowed)
			)
			(placement
				(enabled no)
				(sheetname "")
			)
			(fill
				(thermal_gap 0.5)
				(thermal_bridge_width 0.5)
				(island_removal_mode 0)
			)
			(polygon
				(pts
					(arc
						(start 326.700388 4.193794)
						(mid 324.846188 4.193794)
						(end 326.700388 4.193794)
					)
				)
			)
		)
		(zone
			(layers "F.Cu" "B.Cu" "In1.Cu" "In2.Cu" "In3.Cu" "In4.Cu" "In5.Cu" "In6.Cu"
				"In7.Cu" "In8.Cu" "In9.Cu" "In10.Cu" "In11.Cu" "In12.Cu" "In13.Cu" "In14.Cu"
				"In15.Cu" "In16.Cu"
			)
			(hatch none 0.5)
			(connect_pads
				(clearance 0)
			)
			(min_thickness 0.25)
			(keepout
				(tracks not_allowed)
				(vias allowed)
				(pads allowed)
				(copperpour not_allowed)
				(footprints allowed)
			)
			(placement
				(enabled no)
				(sheetname "")
			)
			(fill
				(thermal_gap 0.5)
				(thermal_bridge_width 0.5)
				(island_removal_mode 0)
			)
			(polygon
				(pts
					(arc
						(start 333.050388 1.653794)
						(mid 331.196188 1.653794)
						(end 333.050388 1.653794)
					)
				)
			)
		)
		(zone
			(layers "F.Cu" "B.Cu" "In1.Cu" "In2.Cu" "In3.Cu" "In4.Cu" "In5.Cu" "In6.Cu"
				"In7.Cu" "In8.Cu" "In9.Cu" "In10.Cu" "In11.Cu" "In12.Cu" "In13.Cu" "In14.Cu"
				"In15.Cu" "In16.Cu"
			)
			(hatch none 0.5)
			(connect_pads
				(clearance 0)
			)
			(min_thickness 0.25)
			(keepout
				(tracks not_allowed)
				(vias allowed)
				(pads allowed)
				(copperpour not_allowed)
				(footprints allowed)
			)
			(placement
				(enabled no)
				(sheetname "")
			)
			(fill
				(thermal_gap 0.5)
				(thermal_bridge_width 0.5)
				(island_removal_mode 0)
			)
			(polygon
				(pts
					(arc
						(start 333.050388 4.193794)
						(mid 331.196188 4.193794)
						(end 333.050388 4.193794)
					)
				)
			)
		)
		(zone
			(layer "B.Cu")
			(hatch none 0.5)
			(connect_pads
				(clearance 0)
			)
			(min_thickness 0.25)
			(keepout
				(tracks not_allowed)
				(vias allowed)
				(pads allowed)
				(copperpour not_allowed)
				(footprints allowed)
			)
			(placement
				(enabled no)
				(sheetname "")
			)
			(fill
				(thermal_gap 0.5)
				(thermal_bridge_width 0.5)
				(island_removal_mode 0)
			)
			(polygon
				(pts
					(xy 328.122788 2.375154) (xy 328.122788 2.470658) (xy 328.719688 2.470658) (xy 328.719688 2.877058)
					(xy 328.122788 2.877058) (xy 328.122788 2.97053) (xy 328.719688 2.97053) (xy 328.719688 3.37693)
					(xy 328.122788 3.37693) (xy 328.122788 3.472434) (xy 328.821288 3.472434) (xy 328.821288 2.375154)
				)
			)
		)
	)
)
